# S9S_MB_2U (Grand Teton) — schematic netlist excerpt (pin names and nets, part order shuffled) for the footprints in the layout excerpt that follows; sources: Cadence DE-HDL packaged netlist, KiCad conversion of 03242023_DA0F0TMBIJ0_F0T_Motherboard_J_brd_V01_OCP.brd

C55  Q_CAP  10UF 16V 10% X6S  pkg C0805  page 99 : A = P12V_S3_AUX_CPU1_NVDIMM ; B = GND
R4089  Q_RES  33.2 1% CHIP  pkg 0402LF  page 14 : A = H_CPU0_PMSYNC_CPU1_R1 ; B = H_CPU0_PMSYNC_CPU1
PR3911  Q_RES  0 5% CHIP  pkg 0402LF  page 302 : A = HSC_VDD_R_2 ; B = HSC_VDD

(kicad_pcb
	(version 20260206)
	(generator "pcbnew")
	(generator_version "10.0")
	(general
		(thickness 1.6)
		(legacy_teardrops no)
	)
	(paper "A4")
	(title_block
		(title "03242023_DA0F0TMBIJ0_F0T_Motherboard_J_brd_V01_OCP.brd")
		(comment 1 "Grand Teton / footprints 4228-4230 of 6105")
	)
	(layers
		(0 "F.Cu" signal "TOP")
		(4 "In1.Cu" signal "GND")
		(6 "In2.Cu" signal "IN1")
		(8 "In3.Cu" signal "GND1")
		(10 "In4.Cu" signal "IN2")
		(12 "In5.Cu" signal "GND2")
		(14 "In6.Cu" signal "IN3")
		(16 "In7.Cu" signal "GND3")
		(18 "In8.Cu" signal "VCC")
		(20 "In9.Cu" signal "VCC1")
		(22 "In10.Cu" signal "GND4")
		(24 "In11.Cu" signal "IN4")
		(26 "In12.Cu" signal "GND5")
		(28 "In13.Cu" signal "IN5")
		(30 "In14.Cu" signal "GND6")
		(32 "In15.Cu" signal "IN6")
		(34 "In16.Cu" signal "GND7")
		(2 "B.Cu" signal "BOTTOM")
		(9 "F.Adhes" user "F.Adhesive")
		(11 "B.Adhes" user "B.Adhesive")
		(13 "F.Paste" user "Package Geometry/Pastemask Top")
		(15 "B.Paste" user "Package Geometry/Pastemask Bottom")
		(5 "F.SilkS" user "Ref Des/Silkscreen Top")
		(7 "B.SilkS" user "Ref Des/Silkscreen Bottom")
		(1 "F.Mask" user "Board Geometry/Soldermask Top")
		(3 "B.Mask" user "Board Geometry/Soldermask Bottom")
		(17 "Dwgs.User" user "User.Drawings")
		(19 "Cmts.User" user "User.Comments")
		(21 "Eco1.User" user "User.Eco1")
		(23 "Eco2.User" user "User.Eco2")
		(25 "Edge.Cuts" user "Board Geometry/Outline")
		(27 "Margin" user)
		(31 "F.CrtYd" user "Package Geometry/Place Bound Top")
		(29 "B.CrtYd" user "Package Geometry/Place Bound Bottom")
		(35 "F.Fab" user "Ref Des/Assembly Top")
		(33 "B.Fab" user "Ref Des/Assembly Bottom")
	)
	(footprint ""
		(layer "B.Cu")
		(at 155.792932 -238.728758)
		(property "Reference" "R4089"
			(at 0 0 0)
			(layer "B.SilkS")
			(hide yes)
			(effects
				(font
					(size 1.27 1.27)
				)
				(justify mirror)
			)
		)
		(property "Value" ""
			(at 0 0 0)
			(layer "B.Fab")
			(effects
				(font
					(size 1.27 1.27)
				)
				(justify mirror)
			)
		)
		(duplicate_pad_numbers_are_jumpers no)
		(fp_line
			(start -0.7874 -0.406146)
			(end -0.7874 0.406146)
			(stroke
				(width 0.1524)
				(type default)
			)
			(layer "B.SilkS")
		)
		(fp_line
			(start -0.7874 0.406146)
			(end 0.7874 0.406146)
			(stroke
				(width 0.1524)
				(type default)
			)
			(layer "B.SilkS")
		)
		(fp_line
			(start 0.7874 -0.406146)
			(end -0.7874 -0.406146)
			(stroke
				(width 0.1524)
				(type default)
			)
			(layer "B.SilkS")
		)
		(fp_line
			(start 0.7874 0.406146)
			(end 0.7874 -0.406146)
			(stroke
				(width 0.1524)
				(type default)
			)
			(layer "B.SilkS")
		)
		(fp_line
			(start -0.67945 -0.3048)
			(end -0.67945 0.3048)
			(stroke
				(width 0.1)
				(type default)
			)
			(layer "B.Fab")
		)
		(fp_line
			(start -0.67945 0.3048)
			(end -0.120396 0.3048)
			(stroke
				(width 0.1)
				(type default)
			)
			(layer "B.Fab")
		)
		(fp_line
			(start -0.12065 -0.2794)
			(end -0.120396 -0.3048)
			(stroke
				(width 0.1)
				(type default)
			)
			(layer "B.Fab")
		)
		(fp_line
			(start -0.120396 -0.3048)
			(end -0.67945 -0.3048)
			(stroke
				(width 0.1)
				(type default)
			)
			(layer "B.Fab")
		)
		(fp_line
			(start -0.120396 0.2794)
			(end 0.12065 0.2794)
			(stroke
				(width 0.1)
				(type default)
			)
			(layer "B.Fab")
		)
		(fp_line
			(start -0.120396 0.3048)
			(end -0.120396 0.2794)
			(stroke
				(width 0.1)
				(type default)
			)
			(layer "B.Fab")
		)
		(fp_line
			(start 0.120396 0.3048)
			(end 0.67945 0.3048)
			(stroke
				(width 0.1)
				(type default)
			)
			(layer "B.Fab")
		)
		(fp_line
			(start 0.12065 -0.305054)
			(end 0.12065 -0.2794)
			(stroke
				(width 0.1)
				(type default)
			)
			(layer "B.Fab")
		)
		(fp_line
			(start 0.12065 -0.2794)
			(end -0.12065 -0.2794)
			(stroke
				(width 0.1)
				(type default)
			)
			(layer "B.Fab")
		)
		(fp_line
			(start 0.12065 0.2794)
			(end 0.120396 0.3048)
			(stroke
				(width 0.1)
				(type default)
			)
			(layer "B.Fab")
		)
		(fp_line
			(start 0.67945 -0.305054)
			(end 0.12065 -0.305054)
			(stroke
				(width 0.1)
				(type default)
			)
			(layer "B.Fab")
		)
		(fp_line
			(start 0.67945 0.3048)
			(end 0.67945 -0.305054)
			(stroke
				(width 0.1)
				(type default)
			)
			(layer "B.Fab")
		)
		(pad "1" smd circle
			(at 0.40005 0 180)
			(size 0 0)
			(layers "B.Cu" "B.Mask" "B.Paste")
			(net "H_CPU0_PMSYNC_CPU1_R1")
		)
		(pad "2" smd circle
			(at -0.40005 0 180)
			(size 0 0)
			(layers "B.Cu" "B.Mask" "B.Paste")
			(net "H_CPU0_PMSYNC_CPU1")
		)
	)
	(footprint ""
		(layer "B.Cu")
		(at 60.959746 -321.554856 -90)
		(property "Reference" "C55"
			(at 0 0 90)
			(layer "B.SilkS")
			(hide yes)
			(effects
				(font
					(size 1.27 1.27)
				)
				(justify mirror)
			)
		)
		(property "Value" ""
			(at 0 0 90)
			(layer "B.Fab")
			(effects
				(font
					(size 1.27 1.27)
				)
				(justify mirror)
			)
		)
		(duplicate_pad_numbers_are_jumpers no)
		(fp_line
			(start -1.524 0.762)
			(end 1.524 0.762)
			(stroke
				(width 0.1524)
				(type default)
			)
			(layer "B.SilkS")
		)
		(fp_line
			(start 1.524 0.762)
			(end 1.524 -0.762)
			(stroke
				(width 0.1524)
				(type default)
			)
			(layer "B.SilkS")
		)
		(fp_line
			(start -1.524 -0.762)
			(end -1.524 0.762)
			(stroke
				(width 0.1524)
				(type default)
			)
			(layer "B.SilkS")
		)
		(fp_line
			(start 1.524 -0.762)
			(end -1.524 -0.762)
			(stroke
				(width 0.1524)
				(type default)
			)
			(layer "B.SilkS")
		)
		(fp_line
			(start -1.1049 0.724916)
			(end -1.1049 -0.724916)
			(stroke
				(width 0.1)
				(type default)
			)
			(layer "B.Fab")
		)
		(fp_line
			(start 1.1049 0.724916)
			(end -1.1049 0.724916)
			(stroke
				(width 0.1)
				(type default)
			)
			(layer "B.Fab")
		)
		(fp_line
			(start -1.1049 -0.724916)
			(end 1.1049 -0.724916)
			(stroke
				(width 0.1)
				(type default)
			)
			(layer "B.Fab")
		)
		(fp_line
			(start 1.1049 -0.724916)
			(end 1.1049 0.724916)
			(stroke
				(width 0.1)
				(type default)
			)
			(layer "B.Fab")
		)
		(pad "1" smd rect
			(at 0.889 0 270)
			(size 1.016 1.27)
			(layers "B.Cu" "B.Mask" "B.Paste")
			(net "P12V_S3_AUX_CPU1_NVDIMM")
		)
		(pad "2" smd rect
			(at -0.889 0 270)
			(size 1.016 1.27)
			(layers "B.Cu" "B.Mask" "B.Paste")
			(net "GND")
		)
	)
	(footprint ""
		(layer "B.Cu")
		(at 205.307438 -403.804882 -90)
		(property "Reference" "PR3911"
			(at 0 0 90)
			(layer "B.SilkS")
			(hide yes)
			(effects
				(font
					(size 1.27 1.27)
				)
				(justify mirror)
			)
		)
		(property "Value" ""
			(at 0 0 90)
			(layer "B.Fab")
			(effects
				(font
					(size 1.27 1.27)
				)
				(justify mirror)
			)
		)
		(duplicate_pad_numbers_are_jumpers no)
		(fp_line
			(start -0.7874 0.4064)
			(end 0.7874 0.4064)
			(stroke
				(width 0.1524)
				(type default)
			)
			(layer "B.SilkS")
		)
		(fp_line
			(start 0.7874 0.4064)
			(end 0.7874 -0.4064)
			(stroke
				(width 0.1524)
				(type default)
			)
			(layer "B.SilkS")
		)
		(fp_line
			(start -0.7874 -0.4064)
			(end -0.7874 0.4064)
			(stroke
				(width 0.1524)
				(type default)
			)
			(layer "B.SilkS")
		)
		(fp_line
			(start 0.7874 -0.4064)
			(end -0.7874 -0.4064)
			(stroke
				(width 0.1524)
				(type default)
			)
			(layer "B.SilkS")
		)
		(fp_line
			(start -0.67945 0.3048)
			(end -0.120396 0.3048)
			(stroke
				(width 0.1)
				(type default)
			)
			(layer "B.Fab")
		)
		(fp_line
			(start -0.120396 0.3048)
			(end -0.120396 0.2794)
			(stroke
				(width 0.1)
				(type default)
			)
			(layer "B.Fab")
		)
		(fp_line
			(start 0.12065 0.3048)
			(end 0.67945 0.3048)
			(stroke
				(width 0.1)
				(type default)
			)
			(layer "B.Fab")
		)
		(fp_line
			(start 0.67945 0.3048)
			(end 0.67945 -0.305054)
			(stroke
				(width 0.1)
				(type default)
			)
			(layer "B.Fab")
		)
		(fp_line
			(start -0.120396 0.2794)
			(end 0.12065 0.2794)
			(stroke
				(width 0.1)
				(type default)
			)
			(layer "B.Fab")
		)
		(fp_line
			(start 0.12065 0.2794)
			(end 0.12065 0.3048)
			(stroke
				(width 0.1)
				(type default)
			)
			(layer "B.Fab")
		)
		(fp_line
			(start -0.12065 -0.2794)
			(end -0.12065 -0.3048)
			(stroke
				(width 0.1)
				(type default)
			)
			(layer "B.Fab")
		)
		(fp_line
			(start 0.12065 -0.2794)
			(end -0.12065 -0.2794)
			(stroke
				(width 0.1)
				(type default)
			)
			(layer "B.Fab")
		)
		(fp_line
			(start -0.67945 -0.3048)
			(end -0.67945 0.3048)
			(stroke
				(width 0.1)
				(type default)
			)
			(layer "B.Fab")
		)
		(fp_line
			(start -0.12065 -0.3048)
			(end -0.67945 -0.3048)
			(stroke
				(width 0.1)
				(type default)
			)
			(layer "B.Fab")
		)
		(fp_line
			(start 0.12065 -0.305054)
			(end 0.12065 -0.2794)
			(stroke
				(width 0.1)
				(type default)
			)
			(layer "B.Fab")
		)
		(fp_line
			(start 0.67945 -0.305054)
			(end 0.12065 -0.305054)
			(stroke
				(width 0.1)
				(type default)
			)
			(layer "B.Fab")
		)
		(pad "1" smd circle
			(at 0.40005 0 90)
			(size 0 0)
			(layers "B.Cu" "B.Mask" "B.Paste")
			(net "HSC_VDD_R_2")
		)
		(pad "2" smd circle
			(at -0.40005 0 90)
			(size 0 0)
			(layers "B.Cu" "B.Mask" "B.Paste")
			(net "HSC_VDD")
		)
	)
)
